(kicad_pcb
	(version 20260206)
	(generator "pcbnew")
	(generator_version "10.0")
	(general
		(thickness 1.6)
		(legacy_teardrops no)
	)
	(paper "A4")
	(title_block
		(title "01162023_DA0F0TEBIF0_F0T_Expander_BD_F_brd_V02_OCP.brd")
		(comment 1 "Grand Teton / footprints 1655-1661 of 9728")
	)
	(layers
		(0 "F.Cu" signal "TOP")
		(4 "In1.Cu" signal "GND")
		(6 "In2.Cu" signal "VCC")
		(8 "In3.Cu" signal "VCC1")
		(10 "In4.Cu" signal "GND1")
		(12 "In5.Cu" signal "IN1")
		(14 "In6.Cu" signal "GND2")
		(16 "In7.Cu" signal "IN2")
		(18 "In8.Cu" signal "GND3")
		(20 "In9.Cu" signal "IN3")
		(22 "In10.Cu" signal "GND4")
		(24 "In11.Cu" signal "IN4")
		(26 "In12.Cu" signal "GND5")
		(28 "In13.Cu" signal "IN5")
		(30 "In14.Cu" signal "GND6")
		(32 "In15.Cu" signal "IN6")
		(34 "In16.Cu" signal "GND7")
		(2 "B.Cu" signal "BOTTOM")
		(9 "F.Adhes" user "F.Adhesive")
		(11 "B.Adhes" user "B.Adhesive")
		(13 "F.Paste" user "Package Geometry/Pastemask Top")
		(15 "B.Paste" user "Package Geometry/Pastemask Bottom")
		(5 "F.SilkS" user "Ref Des/Silkscreen Top")
		(7 "B.SilkS" user "Ref Des/Silkscreen Bottom")
		(1 "F.Mask" user "Board Geometry/Soldermask Top")
		(3 "B.Mask" user "Board Geometry/Soldermask Bottom")
		(17 "Dwgs.User" user "User.Drawings")
		(19 "Cmts.User" user "User.Comments")
		(21 "Eco1.User" user "User.Eco1")
		(23 "Eco2.User" user "User.Eco2")
		(25 "Edge.Cuts" user "Board Geometry/Outline")
		(27 "Margin" user)
		(31 "F.CrtYd" user "Package Geometry/Place Bound Top")
		(29 "B.CrtYd" user "Package Geometry/Place Bound Bottom")
		(35 "F.Fab" user "Ref Des/Assembly Top")
		(33 "B.Fab" user "Ref Des/Assembly Bottom")
	)
	(footprint ""
		(layer "F.Cu")
		(at 146.361912 -311.007252 -135)
		(property "Reference" "R1324"
			(at 0 0 225)
			(layer "F.SilkS")
			(hide yes)
			(effects
				(font
					(size 1.27 1.27)
				)
			)
		)
		(property "Value" ""
			(at 0 0 225)
			(layer "F.Fab")
			(effects
				(font
					(size 1.27 1.27)
				)
			)
		)
		(duplicate_pad_numbers_are_jumpers no)
		(fp_line
			(start 0.787389 0.406267)
			(end -0.787389 0.406267)
			(stroke
				(width 0.1524)
				(type default)
			)
			(layer "F.SilkS")
		)
		(fp_line
			(start 0.787389 -0.406267)
			(end 0.787389 0.406267)
			(stroke
				(width 0.1524)
				(type default)
			)
			(layer "F.SilkS")
		)
		(fp_line
			(start -0.787389 0.406267)
			(end -0.787389 -0.406267)
			(stroke
				(width 0.1524)
				(type default)
			)
			(layer "F.SilkS")
		)
		(fp_line
			(start -0.787389 -0.406267)
			(end 0.787389 -0.406267)
			(stroke
				(width 0.1524)
				(type default)
			)
			(layer "F.SilkS")
		)
		(fp_line
			(start 0.679446 0.30479)
			(end 0.120515 0.30479)
			(stroke
				(width 0.1)
				(type default)
			)
			(layer "F.Fab")
		)
		(fp_line
			(start 0.120515 0.30479)
			(end 0.120335 0.279466)
			(stroke
				(width 0.1)
				(type default)
			)
			(layer "F.Fab")
		)
		(fp_line
			(start 0.120335 0.279466)
			(end -0.120695 0.279466)
			(stroke
				(width 0.1)
				(type default)
			)
			(layer "F.Fab")
		)
		(fp_line
			(start 0.679446 -0.30479)
			(end 0.679446 0.30479)
			(stroke
				(width 0.1)
				(type default)
			)
			(layer "F.Fab")
		)
		(fp_line
			(start -0.120515 0.30479)
			(end -0.679446 0.30479)
			(stroke
				(width 0.1)
				(type default)
			)
			(layer "F.Fab")
		)
		(fp_line
			(start -0.120695 0.279466)
			(end -0.120515 0.30479)
			(stroke
				(width 0.1)
				(type default)
			)
			(layer "F.Fab")
		)
		(fp_line
			(start 0.120695 -0.279466)
			(end 0.120515 -0.30479)
			(stroke
				(width 0.1)
				(type default)
			)
			(layer "F.Fab")
		)
		(fp_line
			(start 0.120515 -0.30479)
			(end 0.679446 -0.30479)
			(stroke
				(width 0.1)
				(type default)
			)
			(layer "F.Fab")
		)
		(fp_line
			(start -0.679446 0.30479)
			(end -0.679446 -0.305149)
			(stroke
				(width 0.1)
				(type default)
			)
			(layer "F.Fab")
		)
		(fp_line
			(start -0.120695 -0.279466)
			(end 0.120695 -0.279466)
			(stroke
				(width 0.1)
				(type default)
			)
			(layer "F.Fab")
		)
		(fp_line
			(start -0.120695 -0.304969)
			(end -0.120695 -0.279466)
			(stroke
				(width 0.1)
				(type default)
			)
			(layer "F.Fab")
		)
		(fp_line
			(start -0.679446 -0.305149)
			(end -0.120695 -0.304969)
			(stroke
				(width 0.1)
				(type default)
			)
			(layer "F.Fab")
		)
		(pad "1" smd circle
			(at -0.40005 0 225)
			(size 0 0)
			(layers "F.Cu" "F.Mask" "F.Paste")
			(net "PU_PEX1_PAD_TRI_L")
		)
		(pad "2" smd circle
			(at 0.40005 0 225)
			(size 0 0)
			(layers "F.Cu" "F.Mask" "F.Paste")
			(net "P1V8_PEX")
		)
	)
	(footprint ""
		(layer "F.Cu")
		(at 250.039886 -70.52437 90)
		(property "Reference" "PC405"
			(at 0 0 90)
			(layer "F.SilkS")
			(hide yes)
			(effects
				(font
					(size 1.27 1.27)
				)
			)
		)
		(property "Value" ""
			(at 0 0 90)
			(layer "F.Fab")
			(effects
				(font
					(size 1.27 1.27)
				)
			)
		)
		(duplicate_pad_numbers_are_jumpers no)
		(fp_line
			(start 1.524 -0.762)
			(end 1.524 0.762)
			(stroke
				(width 0.1524)
				(type default)
			)
			(layer "F.SilkS")
		)
		(fp_line
			(start -1.524 -0.762)
			(end 1.524 -0.762)
			(stroke
				(width 0.1524)
				(type default)
			)
			(layer "F.SilkS")
		)
		(fp_line
			(start 1.524 0.762)
			(end -1.524 0.762)
			(stroke
				(width 0.1524)
				(type default)
			)
			(layer "F.SilkS")
		)
		(fp_line
			(start -1.524 0.762)
			(end -1.524 -0.762)
			(stroke
				(width 0.1524)
				(type default)
			)
			(layer "F.SilkS")
		)
		(fp_line
			(start 1.1049 -0.724916)
			(end -1.1049 -0.724916)
			(stroke
				(width 0.1)
				(type default)
			)
			(layer "F.Fab")
		)
		(fp_line
			(start -1.1049 -0.724916)
			(end -1.1049 0.724916)
			(stroke
				(width 0.1)
				(type default)
			)
			(layer "F.Fab")
		)
		(fp_line
			(start 1.1049 0.724916)
			(end 1.1049 -0.724916)
			(stroke
				(width 0.1)
				(type default)
			)
			(layer "F.Fab")
		)
		(fp_line
			(start -1.1049 0.724916)
			(end 1.1049 0.724916)
			(stroke
				(width 0.1)
				(type default)
			)
			(layer "F.Fab")
		)
		(pad "1" smd rect
			(at -0.889 0 270)
			(size 1.016 1.27)
			(layers "F.Cu" "F.Mask" "F.Paste")
			(net "P12V_SSD8_R")
		)
		(pad "2" smd rect
			(at 0.889 0 270)
			(size 1.016 1.27)
			(layers "F.Cu" "F.Mask" "F.Paste")
			(net "GND")
		)
	)
	(footprint ""
		(layer "F.Cu")
		(at 444.09233 -32.739584 180)
		(property "Reference" "C724"
			(at 0 0 180)
			(layer "F.SilkS")
			(hide yes)
			(effects
				(font
					(size 1.27 1.27)
				)
			)
		)
		(property "Value" ""
			(at 0 0 180)
			(layer "F.Fab")
			(effects
				(font
					(size 1.27 1.27)
				)
			)
		)
		(duplicate_pad_numbers_are_jumpers no)
		(fp_line
			(start 0.299974 0.150114)
			(end -0.299974 0.150114)
			(stroke
				(width 0.1)
				(type default)
			)
			(layer "F.Fab")
		)
		(fp_line
			(start 0.299974 -0.150114)
			(end 0.299974 0.150114)
			(stroke
				(width 0.1)
				(type default)
			)
			(layer "F.Fab")
		)
		(fp_line
			(start -0.299974 0.150114)
			(end -0.299974 -0.150114)
			(stroke
				(width 0.1)
				(type default)
			)
			(layer "F.Fab")
		)
		(fp_line
			(start -0.299974 -0.150114)
			(end 0.299974 -0.150114)
			(stroke
				(width 0.1)
				(type default)
			)
			(layer "F.Fab")
		)
		(pad "1" smd rect
			(at -0.2667 0 180)
			(size 0.3048 0.381)
			(layers "F.Cu" "F.Mask" "F.Paste")
			(net "P5E_PEX3_STN2_TX_DP<34>")
		)
		(pad "2" smd rect
			(at 0.2667 0 180)
			(size 0.3048 0.381)
			(layers "F.Cu" "F.Mask" "F.Paste")
			(net "P5E_PEX3_STN2_TX_C_DP<34>")
		)
	)
	(footprint ""
		(layer "F.Cu")
		(at 440.184032 -289.230816 90)
		(property "Reference" "R4001"
			(at 0 0 90)
			(layer "F.SilkS")
			(hide yes)
			(effects
				(font
					(size 1.27 1.27)
				)
			)
		)
		(property "Value" ""
			(at 0 0 90)
			(layer "F.Fab")
			(effects
				(font
					(size 1.27 1.27)
				)
			)
		)
		(duplicate_pad_numbers_are_jumpers no)
		(fp_line
			(start 0.7874 -0.4064)
			(end 0.7874 0.4064)
			(stroke
				(width 0.1524)
				(type default)
			)
			(layer "F.SilkS")
		)
		(fp_line
			(start -0.7874 -0.4064)
			(end 0.7874 -0.4064)
			(stroke
				(width 0.1524)
				(type default)
			)
			(layer "F.SilkS")
		)
		(fp_line
			(start 0.7874 0.4064)
			(end -0.7874 0.4064)
			(stroke
				(width 0.1524)
				(type default)
			)
			(layer "F.SilkS")
		)
		(fp_line
			(start -0.7874 0.4064)
			(end -0.7874 -0.4064)
			(stroke
				(width 0.1524)
				(type default)
			)
			(layer "F.SilkS")
		)
		(fp_line
			(start -0.12065 -0.305054)
			(end -0.12065 -0.2794)
			(stroke
				(width 0.1)
				(type default)
			)
			(layer "F.Fab")
		)
		(fp_line
			(start -0.67945 -0.305054)
			(end -0.12065 -0.305054)
			(stroke
				(width 0.1)
				(type default)
			)
			(layer "F.Fab")
		)
		(fp_line
			(start 0.67945 -0.3048)
			(end 0.67945 0.3048)
			(stroke
				(width 0.1)
				(type default)
			)
			(layer "F.Fab")
		)
		(fp_line
			(start 0.12065 -0.3048)
			(end 0.67945 -0.3048)
			(stroke
				(width 0.1)
				(type default)
			)
			(layer "F.Fab")
		)
		(fp_line
			(start 0.12065 -0.2794)
			(end 0.12065 -0.3048)
			(stroke
				(width 0.1)
				(type default)
			)
			(layer "F.Fab")
		)
		(fp_line
			(start -0.12065 -0.2794)
			(end 0.12065 -0.2794)
			(stroke
				(width 0.1)
				(type default)
			)
			(layer "F.Fab")
		)
		(fp_line
			(start 0.120396 0.2794)
			(end -0.12065 0.2794)
			(stroke
				(width 0.1)
				(type default)
			)
			(layer "F.Fab")
		)
		(fp_line
			(start -0.12065 0.2794)
			(end -0.12065 0.3048)
			(stroke
				(width 0.1)
				(type default)
			)
			(layer "F.Fab")
		)
		(fp_line
			(start 0.67945 0.3048)
			(end 0.120396 0.3048)
			(stroke
				(width 0.1)
				(type default)
			)
			(layer "F.Fab")
		)
		(fp_line
			(start 0.120396 0.3048)
			(end 0.120396 0.2794)
			(stroke
				(width 0.1)
				(type default)
			)
			(layer "F.Fab")
		)
		(fp_line
			(start -0.12065 0.3048)
			(end -0.67945 0.3048)
			(stroke
				(width 0.1)
				(type default)
			)
			(layer "F.Fab")
		)
		(fp_line
			(start -0.67945 0.3048)
			(end -0.67945 -0.305054)
			(stroke
				(width 0.1)
				(type default)
			)
			(layer "F.Fab")
		)
		(pad "1" smd circle
			(at -0.40005 0 90)
			(size 0 0)
			(layers "F.Cu" "F.Mask" "F.Paste")
			(net "SMB_PEX3_PCA9555_SCL")
		)
		(pad "2" smd circle
			(at 0.40005 0 90)
			(size 0 0)
			(layers "F.Cu" "F.Mask" "F.Paste")
			(net "SMB_PEX3_HOST_LS_SCL")
		)
	)
	(footprint ""
		(layer "F.Cu")
		(at 242.535964 -257.975862 -90)
		(property "Reference" "R6533"
			(at 0 0 270)
			(layer "F.SilkS")
			(hide yes)
			(effects
				(font
					(size 1.27 1.27)
				)
			)
		)
		(property "Value" ""
			(at 0 0 270)
			(layer "F.Fab")
			(effects
				(font
					(size 1.27 1.27)
				)
			)
		)
		(duplicate_pad_numbers_are_jumpers no)
		(fp_line
			(start -0.7874 0.4064)
			(end -0.7874 -0.4064)
			(stroke
				(width 0.1524)
				(type default)
			)
			(layer "F.SilkS")
		)
		(fp_line
			(start 0.7874 0.4064)
			(end -0.7874 0.4064)
			(stroke
				(width 0.1524)
				(type default)
			)
			(layer "F.SilkS")
		)
		(fp_line
			(start -0.7874 -0.4064)
			(end 0.7874 -0.4064)
			(stroke
				(width 0.1524)
				(type default)
			)
			(layer "F.SilkS")
		)
		(fp_line
			(start 0.7874 -0.4064)
			(end 0.7874 0.4064)
			(stroke
				(width 0.1524)
				(type default)
			)
			(layer "F.SilkS")
		)
		(fp_line
			(start -0.67945 0.3048)
			(end -0.67945 -0.305054)
			(stroke
				(width 0.1)
				(type default)
			)
			(layer "F.Fab")
		)
		(fp_line
			(start -0.12065 0.3048)
			(end -0.67945 0.3048)
			(stroke
				(width 0.1)
				(type default)
			)
			(layer "F.Fab")
		)
		(fp_line
			(start 0.120396 0.3048)
			(end 0.120396 0.2794)
			(stroke
				(width 0.1)
				(type default)
			)
			(layer "F.Fab")
		)
		(fp_line
			(start 0.67945 0.3048)
			(end 0.120396 0.3048)
			(stroke
				(width 0.1)
				(type default)
			)
			(layer "F.Fab")
		)
		(fp_line
			(start -0.12065 0.2794)
			(end -0.12065 0.3048)
			(stroke
				(width 0.1)
				(type default)
			)
			(layer "F.Fab")
		)
		(fp_line
			(start 0.120396 0.2794)
			(end -0.12065 0.2794)
			(stroke
				(width 0.1)
				(type default)
			)
			(layer "F.Fab")
		)
		(fp_line
			(start -0.12065 -0.2794)
			(end 0.12065 -0.2794)
			(stroke
				(width 0.1)
				(type default)
			)
			(layer "F.Fab")
		)
		(fp_line
			(start 0.12065 -0.2794)
			(end 0.12065 -0.3048)
			(stroke
				(width 0.1)
				(type default)
			)
			(layer "F.Fab")
		)
		(fp_line
			(start 0.12065 -0.3048)
			(end 0.67945 -0.3048)
			(stroke
				(width 0.1)
				(type default)
			)
			(layer "F.Fab")
		)
		(fp_line
			(start 0.67945 -0.3048)
			(end 0.67945 0.3048)
			(stroke
				(width 0.1)
				(type default)
			)
			(layer "F.Fab")
		)
		(fp_line
			(start -0.67945 -0.305054)
			(end -0.12065 -0.305054)
			(stroke
				(width 0.1)
				(type default)
			)
			(layer "F.Fab")
		)
		(fp_line
			(start -0.12065 -0.305054)
			(end -0.12065 -0.2794)
			(stroke
				(width 0.1)
				(type default)
			)
			(layer "F.Fab")
		)
		(pad "1" smd circle
			(at -0.40005 0 270)
			(size 0 0)
			(layers "F.Cu" "F.Mask" "F.Paste")
			(net "P1V25_SERDES_VDDPLL_PEX2")
		)
		(pad "2" smd circle
			(at 0.40005 0 270)
			(size 0 0)
			(layers "F.Cu" "F.Mask" "F.Paste")
			(net "P1V25_SERDES_VDDPLL_PEX2_C10")
		)
	)
	(footprint ""
		(layer "F.Cu")
		(at 12.609322 -119.105426 -90)
		(property "Reference" "R5862"
			(at 0 0 270)
			(layer "F.SilkS")
			(hide yes)
			(effects
				(font
					(size 1.27 1.27)
				)
			)
		)
		(property "Value" ""
			(at 0 0 270)
			(layer "F.Fab")
			(effects
				(font
					(size 1.27 1.27)
				)
			)
		)
		(duplicate_pad_numbers_are_jumpers no)
		(fp_line
			(start -0.7874 0.4064)
			(end -0.7874 -0.4064)
			(stroke
				(width 0.1524)
				(type default)
			)
			(layer "F.SilkS")
		)
		(fp_line
			(start 0.7874 0.4064)
			(end -0.7874 0.4064)
			(stroke
				(width 0.1524)
				(type default)
			)
			(layer "F.SilkS")
		)
		(fp_line
			(start -0.7874 -0.4064)
			(end 0.7874 -0.4064)
			(stroke
				(width 0.1524)
				(type default)
			)
			(layer "F.SilkS")
		)
		(fp_line
			(start 0.7874 -0.4064)
			(end 0.7874 0.4064)
			(stroke
				(width 0.1524)
				(type default)
			)
			(layer "F.SilkS")
		)
		(fp_line
			(start -0.67945 0.3048)
			(end -0.67945 -0.305054)
			(stroke
				(width 0.1)
				(type default)
			)
			(layer "F.Fab")
		)
		(fp_line
			(start -0.12065 0.3048)
			(end -0.67945 0.3048)
			(stroke
				(width 0.1)
				(type default)
			)
			(layer "F.Fab")
		)
		(fp_line
			(start 0.120396 0.3048)
			(end 0.120396 0.2794)
			(stroke
				(width 0.1)
				(type default)
			)
			(layer "F.Fab")
		)
		(fp_line
			(start 0.67945 0.3048)
			(end 0.120396 0.3048)
			(stroke
				(width 0.1)
				(type default)
			)
			(layer "F.Fab")
		)
		(fp_line
			(start -0.12065 0.2794)
			(end -0.12065 0.3048)
			(stroke
				(width 0.1)
				(type default)
			)
			(layer "F.Fab")
		)
		(fp_line
			(start 0.120396 0.2794)
			(end -0.12065 0.2794)
			(stroke
				(width 0.1)
				(type default)
			)
			(layer "F.Fab")
		)
		(fp_line
			(start -0.12065 -0.2794)
			(end 0.12065 -0.2794)
			(stroke
				(width 0.1)
				(type default)
			)
			(layer "F.Fab")
		)
		(fp_line
			(start 0.12065 -0.2794)
			(end 0.12065 -0.3048)
			(stroke
				(width 0.1)
				(type default)
			)
			(layer "F.Fab")
		)
		(fp_line
			(start 0.12065 -0.3048)
			(end 0.67945 -0.3048)
			(stroke
				(width 0.1)
				(type default)
			)
			(layer "F.Fab")
		)
		(fp_line
			(start 0.67945 -0.3048)
			(end 0.67945 0.3048)
			(stroke
				(width 0.1)
				(type default)
			)
			(layer "F.Fab")
		)
		(fp_line
			(start -0.67945 -0.305054)
			(end -0.12065 -0.305054)
			(stroke
				(width 0.1)
				(type default)
			)
			(layer "F.Fab")
		)
		(fp_line
			(start -0.12065 -0.305054)
			(end -0.12065 -0.2794)
			(stroke
				(width 0.1)
				(type default)
			)
			(layer "F.Fab")
		)
		(pad "1" smd circle
			(at -0.40005 0 270)
			(size 0 0)
			(layers "F.Cu" "F.Mask" "F.Paste")
			(net "P3V3_NIC0")
		)
		(pad "2" smd circle
			(at 0.40005 0 270)
			(size 0 0)
			(layers "F.Cu" "F.Mask" "F.Paste")
			(net "P3V3_NIC0_PG_G1")
		)
	)
	(footprint ""
		(layer "F.Cu")
		(at 113.509806 -293.5351 90)
		(property "Reference" "PL7"
			(at -4.260596 23.43277 90)
			(unlocked yes)
			(layer "F.SilkS")
			(effects
				(font
					(size 0.7874 0.5842)
					(thickness 0.1524)
				)
				(justify left)
			)
		)
		(property "Value" ""
			(at 0 0 90)
			(layer "F.Fab")
			(effects
				(font
					(size 1.27 1.27)
				)
			)
		)
		(duplicate_pad_numbers_are_jumpers no)
		(fp_line
			(start 4.800092 -3.199892)
			(end 4.800092 -1.6764)
			(stroke
				(width 0.1524)
				(type default)
			)
			(layer "F.SilkS")
		)
		(fp_line
			(start -4.800092 -3.199892)
			(end 4.800092 -3.199892)
			(stroke
				(width 0.1524)
				(type default)
			)
			(layer "F.SilkS")
		)
		(fp_line
			(start -4.800092 -1.6764)
			(end -4.800092 -3.199892)
			(stroke
				(width 0.1524)
				(type default)
			)
			(layer "F.SilkS")
		)
		(fp_line
			(start 4.800092 1.6764)
			(end 4.800092 3.199892)
			(stroke
				(width 0.1524)
				(type default)
			)
			(layer "F.SilkS")
		)
		(fp_line
			(start 4.800092 3.199892)
			(end -4.800092 3.199892)
			(stroke
				(width 0.1524)
				(type default)
			)
			(layer "F.SilkS")
		)
		(fp_line
			(start -4.800092 3.199892)
			(end -4.800092 1.6764)
			(stroke
				(width 0.1524)
				(type default)
			)
			(layer "F.SilkS")
		)
		(fp_line
			(start 4.800092 -3.199892)
			(end 4.800092 3.199892)
			(stroke
				(width 0.1)
				(type default)
			)
			(layer "F.Fab")
		)
		(fp_line
			(start -4.800092 -3.199892)
			(end 4.800092 -3.199892)
			(stroke
				(width 0.1)
				(type default)
			)
			(layer "F.Fab")
		)
		(fp_line
			(start 4.800092 3.199892)
			(end -4.800092 3.199892)
			(stroke
				(width 0.1)
				(type default)
			)
			(layer "F.Fab")
		)
		(fp_line
			(start -4.800092 3.199892)
			(end -4.800092 -3.199892)
			(stroke
				(width 0.1)
				(type default)
			)
			(layer "F.Fab")
		)
		(pad "1" smd rect
			(at -3.074924 0 180)
			(size 3.0988 3.3528)
			(layers "F.Cu" "F.Mask" "F.Paste")
			(net "SW_P0V8_PEX0_PH2")
		)
		(pad "2" smd rect
			(at 3.074924 0 180)
			(size 3.0988 3.3528)
			(layers "F.Cu" "F.Mask" "F.Paste")
			(net "P0V8_PEX0")
		)
	)
)
